(kicad_pcb
	(version 20260206)
	(generator "pcbnew")
	(generator_version "10.0")
	(general
		(thickness 1.6)
		(legacy_teardrops no)
	)
	(paper "A4")
	(title_block
		(title "01162023_DA0F0TEBIF0_F0T_Expander_BD_F_brd_V02_OCP.brd")
		(comment 1 "Grand Teton / footprints 661-668 of 9728")
	)
	(layers
		(0 "F.Cu" signal "TOP")
		(4 "In1.Cu" signal "GND")
		(6 "In2.Cu" signal "VCC")
		(8 "In3.Cu" signal "VCC1")
		(10 "In4.Cu" signal "GND1")
		(12 "In5.Cu" signal "IN1")
		(14 "In6.Cu" signal "GND2")
		(16 "In7.Cu" signal "IN2")
		(18 "In8.Cu" signal "GND3")
		(20 "In9.Cu" signal "IN3")
		(22 "In10.Cu" signal "GND4")
		(24 "In11.Cu" signal "IN4")
		(26 "In12.Cu" signal "GND5")
		(28 "In13.Cu" signal "IN5")
		(30 "In14.Cu" signal "GND6")
		(32 "In15.Cu" signal "IN6")
		(34 "In16.Cu" signal "GND7")
		(2 "B.Cu" signal "BOTTOM")
		(9 "F.Adhes" user "F.Adhesive")
		(11 "B.Adhes" user "B.Adhesive")
		(13 "F.Paste" user "Package Geometry/Pastemask Top")
		(15 "B.Paste" user "Package Geometry/Pastemask Bottom")
		(5 "F.SilkS" user "Ref Des/Silkscreen Top")
		(7 "B.SilkS" user "Ref Des/Silkscreen Bottom")
		(1 "F.Mask" user "Board Geometry/Soldermask Top")
		(3 "B.Mask" user "Board Geometry/Soldermask Bottom")
		(17 "Dwgs.User" user "User.Drawings")
		(19 "Cmts.User" user "User.Comments")
		(21 "Eco1.User" user "User.Eco1")
		(23 "Eco2.User" user "User.Eco2")
		(25 "Edge.Cuts" user "Board Geometry/Outline")
		(27 "Margin" user)
		(31 "F.CrtYd" user "Package Geometry/Place Bound Top")
		(29 "B.CrtYd" user "Package Geometry/Place Bound Bottom")
		(35 "F.Fab" user "Ref Des/Assembly Top")
		(33 "B.Fab" user "Ref Des/Assembly Bottom")
	)
	(footprint ""
		(layer "F.Cu")
		(at 88.65235 -115.400836)
		(property "Reference" "R5854"
			(at 0 0 0)
			(layer "F.SilkS")
			(hide yes)
			(effects
				(font
					(size 1.27 1.27)
				)
			)
		)
		(property "Value" ""
			(at 0 0 0)
			(layer "F.Fab")
			(effects
				(font
					(size 1.27 1.27)
				)
			)
		)
		(duplicate_pad_numbers_are_jumpers no)
		(fp_line
			(start -0.7874 -0.4064)
			(end 0.7874 -0.4064)
			(stroke
				(width 0.1524)
				(type default)
			)
			(layer "F.SilkS")
		)
		(fp_line
			(start -0.7874 0.4064)
			(end -0.7874 -0.4064)
			(stroke
				(width 0.1524)
				(type default)
			)
			(layer "F.SilkS")
		)
		(fp_line
			(start 0.7874 -0.4064)
			(end 0.7874 0.4064)
			(stroke
				(width 0.1524)
				(type default)
			)
			(layer "F.SilkS")
		)
		(fp_line
			(start 0.7874 0.4064)
			(end -0.7874 0.4064)
			(stroke
				(width 0.1524)
				(type default)
			)
			(layer "F.SilkS")
		)
		(fp_line
			(start -0.67945 -0.305054)
			(end -0.12065 -0.305054)
			(stroke
				(width 0.1)
				(type default)
			)
			(layer "F.Fab")
		)
		(fp_line
			(start -0.67945 0.3048)
			(end -0.67945 -0.305054)
			(stroke
				(width 0.1)
				(type default)
			)
			(layer "F.Fab")
		)
		(fp_line
			(start -0.12065 -0.305054)
			(end -0.12065 -0.2794)
			(stroke
				(width 0.1)
				(type default)
			)
			(layer "F.Fab")
		)
		(fp_line
			(start -0.12065 -0.2794)
			(end 0.12065 -0.2794)
			(stroke
				(width 0.1)
				(type default)
			)
			(layer "F.Fab")
		)
		(fp_line
			(start -0.12065 0.2794)
			(end -0.12065 0.3048)
			(stroke
				(width 0.1)
				(type default)
			)
			(layer "F.Fab")
		)
		(fp_line
			(start -0.12065 0.3048)
			(end -0.67945 0.3048)
			(stroke
				(width 0.1)
				(type default)
			)
			(layer "F.Fab")
		)
		(fp_line
			(start 0.120396 0.2794)
			(end -0.12065 0.2794)
			(stroke
				(width 0.1)
				(type default)
			)
			(layer "F.Fab")
		)
		(fp_line
			(start 0.120396 0.3048)
			(end 0.120396 0.2794)
			(stroke
				(width 0.1)
				(type default)
			)
			(layer "F.Fab")
		)
		(fp_line
			(start 0.12065 -0.3048)
			(end 0.67945 -0.3048)
			(stroke
				(width 0.1)
				(type default)
			)
			(layer "F.Fab")
		)
		(fp_line
			(start 0.12065 -0.2794)
			(end 0.12065 -0.3048)
			(stroke
				(width 0.1)
				(type default)
			)
			(layer "F.Fab")
		)
		(fp_line
			(start 0.67945 -0.3048)
			(end 0.67945 0.3048)
			(stroke
				(width 0.1)
				(type default)
			)
			(layer "F.Fab")
		)
		(fp_line
			(start 0.67945 0.3048)
			(end 0.120396 0.3048)
			(stroke
				(width 0.1)
				(type default)
			)
			(layer "F.Fab")
		)
		(pad "1" smd circle
			(at -0.40005 0)
			(size 0 0)
			(layers "F.Cu" "F.Mask" "F.Paste")
			(net "HP_NIC1_EN")
		)
		(pad "2" smd circle
			(at 0.40005 0)
			(size 0 0)
			(layers "F.Cu" "F.Mask" "F.Paste")
			(net "P3V3_NIC1_CO_EN")
		)
	)
	(footprint ""
		(layer "F.Cu")
		(at 143.840708 -343.952322 90)
		(property "Reference" "C2246"
			(at 0 0 90)
			(layer "F.SilkS")
			(hide yes)
			(effects
				(font
					(size 1.27 1.27)
				)
			)
		)
		(property "Value" ""
			(at 0 0 90)
			(layer "F.Fab")
			(effects
				(font
					(size 1.27 1.27)
				)
			)
		)
		(duplicate_pad_numbers_are_jumpers no)
		(fp_line
			(start 0.299974 -0.150114)
			(end 0.299974 0.150114)
			(stroke
				(width 0.1)
				(type default)
			)
			(layer "F.Fab")
		)
		(fp_line
			(start -0.299974 -0.150114)
			(end 0.299974 -0.150114)
			(stroke
				(width 0.1)
				(type default)
			)
			(layer "F.Fab")
		)
		(fp_line
			(start 0.299974 0.150114)
			(end -0.299974 0.150114)
			(stroke
				(width 0.1)
				(type default)
			)
			(layer "F.Fab")
		)
		(fp_line
			(start -0.299974 0.150114)
			(end -0.299974 -0.150114)
			(stroke
				(width 0.1)
				(type default)
			)
			(layer "F.Fab")
		)
		(pad "1" smd rect
			(at -0.2667 0 90)
			(size 0.3048 0.381)
			(layers "F.Cu" "F.Mask" "F.Paste")
			(net "P5E_PEX1_STN5_TX_DN<94>")
		)
		(pad "2" smd rect
			(at 0.2667 0 90)
			(size 0.3048 0.381)
			(layers "F.Cu" "F.Mask" "F.Paste")
			(net "P5E_PEX1_STN5_TX_C_DN<94>")
		)
	)
	(footprint ""
		(layer "F.Cu")
		(at 20.221448 -343.952322 90)
		(property "Reference" "C2153"
			(at 0 0 90)
			(layer "F.SilkS")
			(hide yes)
			(effects
				(font
					(size 1.27 1.27)
				)
			)
		)
		(property "Value" ""
			(at 0 0 90)
			(layer "F.Fab")
			(effects
				(font
					(size 1.27 1.27)
				)
			)
		)
		(duplicate_pad_numbers_are_jumpers no)
		(fp_line
			(start 0.299974 -0.150114)
			(end 0.299974 0.150114)
			(stroke
				(width 0.1)
				(type default)
			)
			(layer "F.Fab")
		)
		(fp_line
			(start -0.299974 -0.150114)
			(end 0.299974 -0.150114)
			(stroke
				(width 0.1)
				(type default)
			)
			(layer "F.Fab")
		)
		(fp_line
			(start 0.299974 0.150114)
			(end -0.299974 0.150114)
			(stroke
				(width 0.1)
				(type default)
			)
			(layer "F.Fab")
		)
		(fp_line
			(start -0.299974 0.150114)
			(end -0.299974 -0.150114)
			(stroke
				(width 0.1)
				(type default)
			)
			(layer "F.Fab")
		)
		(pad "1" smd rect
			(at -0.2667 0 90)
			(size 0.3048 0.381)
			(layers "F.Cu" "F.Mask" "F.Paste")
			(net "P5E_PEX0_STN4_TX_DN<79>")
		)
		(pad "2" smd rect
			(at 0.2667 0 90)
			(size 0.3048 0.381)
			(layers "F.Cu" "F.Mask" "F.Paste")
			(net "P5E_PEX0_STN4_TX_C_DN<79>")
		)
	)
	(footprint ""
		(layer "F.Cu")
		(at 352.920554 -89.502234)
		(property "Reference" "R1615"
			(at 0 0 0)
			(layer "F.SilkS")
			(hide yes)
			(effects
				(font
					(size 1.27 1.27)
				)
			)
		)
		(property "Value" ""
			(at 0 0 0)
			(layer "F.Fab")
			(effects
				(font
					(size 1.27 1.27)
				)
			)
		)
		(duplicate_pad_numbers_are_jumpers no)
		(fp_line
			(start -0.7874 -0.4064)
			(end 0.7874 -0.4064)
			(stroke
				(width 0.1524)
				(type default)
			)
			(layer "F.SilkS")
		)
		(fp_line
			(start -0.7874 0.4064)
			(end -0.7874 -0.4064)
			(stroke
				(width 0.1524)
				(type default)
			)
			(layer "F.SilkS")
		)
		(fp_line
			(start 0.7874 -0.4064)
			(end 0.7874 0.4064)
			(stroke
				(width 0.1524)
				(type default)
			)
			(layer "F.SilkS")
		)
		(fp_line
			(start 0.7874 0.4064)
			(end -0.7874 0.4064)
			(stroke
				(width 0.1524)
				(type default)
			)
			(layer "F.SilkS")
		)
		(fp_line
			(start -0.67945 -0.305054)
			(end -0.12065 -0.305054)
			(stroke
				(width 0.1)
				(type default)
			)
			(layer "F.Fab")
		)
		(fp_line
			(start -0.67945 0.3048)
			(end -0.67945 -0.305054)
			(stroke
				(width 0.1)
				(type default)
			)
			(layer "F.Fab")
		)
		(fp_line
			(start -0.12065 -0.305054)
			(end -0.12065 -0.2794)
			(stroke
				(width 0.1)
				(type default)
			)
			(layer "F.Fab")
		)
		(fp_line
			(start -0.12065 -0.2794)
			(end 0.12065 -0.2794)
			(stroke
				(width 0.1)
				(type default)
			)
			(layer "F.Fab")
		)
		(fp_line
			(start -0.12065 0.2794)
			(end -0.12065 0.3048)
			(stroke
				(width 0.1)
				(type default)
			)
			(layer "F.Fab")
		)
		(fp_line
			(start -0.12065 0.3048)
			(end -0.67945 0.3048)
			(stroke
				(width 0.1)
				(type default)
			)
			(layer "F.Fab")
		)
		(fp_line
			(start 0.120396 0.2794)
			(end -0.12065 0.2794)
			(stroke
				(width 0.1)
				(type default)
			)
			(layer "F.Fab")
		)
		(fp_line
			(start 0.120396 0.3048)
			(end 0.120396 0.2794)
			(stroke
				(width 0.1)
				(type default)
			)
			(layer "F.Fab")
		)
		(fp_line
			(start 0.12065 -0.3048)
			(end 0.67945 -0.3048)
			(stroke
				(width 0.1)
				(type default)
			)
			(layer "F.Fab")
		)
		(fp_line
			(start 0.12065 -0.2794)
			(end 0.12065 -0.3048)
			(stroke
				(width 0.1)
				(type default)
			)
			(layer "F.Fab")
		)
		(fp_line
			(start 0.67945 -0.3048)
			(end 0.67945 0.3048)
			(stroke
				(width 0.1)
				(type default)
			)
			(layer "F.Fab")
		)
		(fp_line
			(start 0.67945 0.3048)
			(end 0.120396 0.3048)
			(stroke
				(width 0.1)
				(type default)
			)
			(layer "F.Fab")
		)
		(pad "1" smd circle
			(at -0.40005 0)
			(size 0 0)
			(layers "F.Cu" "F.Mask" "F.Paste")
			(net "SMB_BIC_I2C9_MUX1_SSD8_R_SDA")
		)
		(pad "2" smd circle
			(at 0.40005 0)
			(size 0 0)
			(layers "F.Cu" "F.Mask" "F.Paste")
			(net "SMB_BIC_I2C9_MUX1_SSD8_SDA")
		)
	)
	(footprint ""
		(layer "F.Cu")
		(at 213.833456 -217.27033)
		(property "Reference" "R4876"
			(at 0 0 0)
			(layer "F.SilkS")
			(hide yes)
			(effects
				(font
					(size 1.27 1.27)
				)
			)
		)
		(property "Value" ""
			(at 0 0 0)
			(layer "F.Fab")
			(effects
				(font
					(size 1.27 1.27)
				)
			)
		)
		(duplicate_pad_numbers_are_jumpers no)
		(fp_line
			(start -0.7874 -0.4064)
			(end 0.7874 -0.4064)
			(stroke
				(width 0.1524)
				(type default)
			)
			(layer "F.SilkS")
		)
		(fp_line
			(start -0.7874 0.4064)
			(end -0.7874 -0.4064)
			(stroke
				(width 0.1524)
				(type default)
			)
			(layer "F.SilkS")
		)
		(fp_line
			(start 0.7874 -0.4064)
			(end 0.7874 0.4064)
			(stroke
				(width 0.1524)
				(type default)
			)
			(layer "F.SilkS")
		)
		(fp_line
			(start 0.7874 0.4064)
			(end -0.7874 0.4064)
			(stroke
				(width 0.1524)
				(type default)
			)
			(layer "F.SilkS")
		)
		(fp_line
			(start -0.67945 -0.305054)
			(end -0.12065 -0.305054)
			(stroke
				(width 0.1)
				(type default)
			)
			(layer "F.Fab")
		)
		(fp_line
			(start -0.67945 0.3048)
			(end -0.67945 -0.305054)
			(stroke
				(width 0.1)
				(type default)
			)
			(layer "F.Fab")
		)
		(fp_line
			(start -0.12065 -0.305054)
			(end -0.12065 -0.2794)
			(stroke
				(width 0.1)
				(type default)
			)
			(layer "F.Fab")
		)
		(fp_line
			(start -0.12065 -0.2794)
			(end 0.12065 -0.2794)
			(stroke
				(width 0.1)
				(type default)
			)
			(layer "F.Fab")
		)
		(fp_line
			(start -0.12065 0.2794)
			(end -0.12065 0.3048)
			(stroke
				(width 0.1)
				(type default)
			)
			(layer "F.Fab")
		)
		(fp_line
			(start -0.12065 0.3048)
			(end -0.67945 0.3048)
			(stroke
				(width 0.1)
				(type default)
			)
			(layer "F.Fab")
		)
		(fp_line
			(start 0.120396 0.2794)
			(end -0.12065 0.2794)
			(stroke
				(width 0.1)
				(type default)
			)
			(layer "F.Fab")
		)
		(fp_line
			(start 0.120396 0.3048)
			(end 0.120396 0.2794)
			(stroke
				(width 0.1)
				(type default)
			)
			(layer "F.Fab")
		)
		(fp_line
			(start 0.12065 -0.3048)
			(end 0.67945 -0.3048)
			(stroke
				(width 0.1)
				(type default)
			)
			(layer "F.Fab")
		)
		(fp_line
			(start 0.12065 -0.2794)
			(end 0.12065 -0.3048)
			(stroke
				(width 0.1)
				(type default)
			)
			(layer "F.Fab")
		)
		(fp_line
			(start 0.67945 -0.3048)
			(end 0.67945 0.3048)
			(stroke
				(width 0.1)
				(type default)
			)
			(layer "F.Fab")
		)
		(fp_line
			(start 0.67945 0.3048)
			(end 0.120396 0.3048)
			(stroke
				(width 0.1)
				(type default)
			)
			(layer "F.Fab")
		)
		(pad "1" smd circle
			(at -0.40005 0)
			(size 0 0)
			(layers "F.Cu" "F.Mask" "F.Paste")
			(net "P1V2_AUX")
		)
		(pad "2" smd circle
			(at 0.40005 0)
			(size 0 0)
			(layers "F.Cu" "F.Mask" "F.Paste")
			(net "SMB_NIC5_SDA")
		)
	)
	(footprint ""
		(layer "F.Cu")
		(at 435.285134 -306.041044 -90)
		(property "Reference" "R6811"
			(at 0 0 270)
			(layer "F.SilkS")
			(hide yes)
			(effects
				(font
					(size 1.27 1.27)
				)
			)
		)
		(property "Value" ""
			(at 0 0 270)
			(layer "F.Fab")
			(effects
				(font
					(size 1.27 1.27)
				)
			)
		)
		(duplicate_pad_numbers_are_jumpers no)
		(fp_line
			(start -0.7874 0.4064)
			(end -0.7874 -0.4064)
			(stroke
				(width 0.1524)
				(type default)
			)
			(layer "F.SilkS")
		)
		(fp_line
			(start 0.7874 0.4064)
			(end -0.7874 0.4064)
			(stroke
				(width 0.1524)
				(type default)
			)
			(layer "F.SilkS")
		)
		(fp_line
			(start -0.7874 -0.4064)
			(end 0.7874 -0.4064)
			(stroke
				(width 0.1524)
				(type default)
			)
			(layer "F.SilkS")
		)
		(fp_line
			(start 0.7874 -0.4064)
			(end 0.7874 0.4064)
			(stroke
				(width 0.1524)
				(type default)
			)
			(layer "F.SilkS")
		)
		(fp_line
			(start -0.67945 0.3048)
			(end -0.67945 -0.305054)
			(stroke
				(width 0.1)
				(type default)
			)
			(layer "F.Fab")
		)
		(fp_line
			(start -0.12065 0.3048)
			(end -0.67945 0.3048)
			(stroke
				(width 0.1)
				(type default)
			)
			(layer "F.Fab")
		)
		(fp_line
			(start 0.120396 0.3048)
			(end 0.120396 0.2794)
			(stroke
				(width 0.1)
				(type default)
			)
			(layer "F.Fab")
		)
		(fp_line
			(start 0.67945 0.3048)
			(end 0.120396 0.3048)
			(stroke
				(width 0.1)
				(type default)
			)
			(layer "F.Fab")
		)
		(fp_line
			(start -0.12065 0.2794)
			(end -0.12065 0.3048)
			(stroke
				(width 0.1)
				(type default)
			)
			(layer "F.Fab")
		)
		(fp_line
			(start 0.120396 0.2794)
			(end -0.12065 0.2794)
			(stroke
				(width 0.1)
				(type default)
			)
			(layer "F.Fab")
		)
		(fp_line
			(start -0.12065 -0.2794)
			(end 0.12065 -0.2794)
			(stroke
				(width 0.1)
				(type default)
			)
			(layer "F.Fab")
		)
		(fp_line
			(start 0.12065 -0.2794)
			(end 0.12065 -0.3048)
			(stroke
				(width 0.1)
				(type default)
			)
			(layer "F.Fab")
		)
		(fp_line
			(start 0.12065 -0.3048)
			(end 0.67945 -0.3048)
			(stroke
				(width 0.1)
				(type default)
			)
			(layer "F.Fab")
		)
		(fp_line
			(start 0.67945 -0.3048)
			(end 0.67945 0.3048)
			(stroke
				(width 0.1)
				(type default)
			)
			(layer "F.Fab")
		)
		(fp_line
			(start -0.67945 -0.305054)
			(end -0.12065 -0.305054)
			(stroke
				(width 0.1)
				(type default)
			)
			(layer "F.Fab")
		)
		(fp_line
			(start -0.12065 -0.305054)
			(end -0.12065 -0.2794)
			(stroke
				(width 0.1)
				(type default)
			)
			(layer "F.Fab")
		)
		(pad "1" smd circle
			(at -0.40005 0 270)
			(size 0 0)
			(layers "F.Cu" "F.Mask" "F.Paste")
			(net "SMB_PEX3_R_SDA")
		)
		(pad "2" smd circle
			(at 0.40005 0 270)
			(size 0 0)
			(layers "F.Cu" "F.Mask" "F.Paste")
			(net "SMB_PEX3_SDA")
		)
	)
	(footprint ""
		(layer "F.Cu")
		(at 198.76135 -151.596852 180)
		(property "Reference" "C217"
			(at 0 0 180)
			(layer "F.SilkS")
			(hide yes)
			(effects
				(font
					(size 1.27 1.27)
				)
			)
		)
		(property "Value" ""
			(at 0 0 180)
			(layer "F.Fab")
			(effects
				(font
					(size 1.27 1.27)
				)
			)
		)
		(duplicate_pad_numbers_are_jumpers no)
		(fp_line
			(start 0.299974 0.150114)
			(end -0.299974 0.150114)
			(stroke
				(width 0.1)
				(type default)
			)
			(layer "F.Fab")
		)
		(fp_line
			(start 0.299974 -0.150114)
			(end 0.299974 0.150114)
			(stroke
				(width 0.1)
				(type default)
			)
			(layer "F.Fab")
		)
		(fp_line
			(start -0.299974 0.150114)
			(end -0.299974 -0.150114)
			(stroke
				(width 0.1)
				(type default)
			)
			(layer "F.Fab")
		)
		(fp_line
			(start -0.299974 -0.150114)
			(end 0.299974 -0.150114)
			(stroke
				(width 0.1)
				(type default)
			)
			(layer "F.Fab")
		)
		(pad "1" smd rect
			(at -0.2667 0 180)
			(size 0.3048 0.381)
			(layers "F.Cu" "F.Mask" "F.Paste")
			(net "P5E_PEX1_STN0_TX_DN<13>")
		)
		(pad "2" smd rect
			(at 0.2667 0 180)
			(size 0.3048 0.381)
			(layers "F.Cu" "F.Mask" "F.Paste")
			(net "P5E_PEX1_STN0_TX_C_DN<13>")
		)
	)
	(footprint ""
		(layer "F.Cu")
		(at 168.367964 -54.067456)
		(property "Reference" "PR214"
			(at 0 0 0)
			(layer "F.SilkS")
			(hide yes)
			(effects
				(font
					(size 1.27 1.27)
				)
			)
		)
		(property "Value" ""
			(at 0 0 0)
			(layer "F.Fab")
			(effects
				(font
					(size 1.27 1.27)
				)
			)
		)
		(duplicate_pad_numbers_are_jumpers no)
		(fp_line
			(start -0.7874 -0.4064)
			(end 0.7874 -0.4064)
			(stroke
				(width 0.1524)
				(type default)
			)
			(layer "F.SilkS")
		)
		(fp_line
			(start -0.7874 0.4064)
			(end -0.7874 -0.4064)
			(stroke
				(width 0.1524)
				(type default)
			)
			(layer "F.SilkS")
		)
		(fp_line
			(start 0.7874 -0.4064)
			(end 0.7874 0.4064)
			(stroke
				(width 0.1524)
				(type default)
			)
			(layer "F.SilkS")
		)
		(fp_line
			(start 0.7874 0.4064)
			(end -0.7874 0.4064)
			(stroke
				(width 0.1524)
				(type default)
			)
			(layer "F.SilkS")
		)
		(fp_line
			(start -0.67945 -0.305054)
			(end -0.12065 -0.305054)
			(stroke
				(width 0.1)
				(type default)
			)
			(layer "F.Fab")
		)
		(fp_line
			(start -0.67945 0.3048)
			(end -0.67945 -0.305054)
			(stroke
				(width 0.1)
				(type default)
			)
			(layer "F.Fab")
		)
		(fp_line
			(start -0.12065 -0.305054)
			(end -0.12065 -0.2794)
			(stroke
				(width 0.1)
				(type default)
			)
			(layer "F.Fab")
		)
		(fp_line
			(start -0.12065 -0.2794)
			(end 0.12065 -0.2794)
			(stroke
				(width 0.1)
				(type default)
			)
			(layer "F.Fab")
		)
		(fp_line
			(start -0.12065 0.2794)
			(end -0.12065 0.3048)
			(stroke
				(width 0.1)
				(type default)
			)
			(layer "F.Fab")
		)
		(fp_line
			(start -0.12065 0.3048)
			(end -0.67945 0.3048)
			(stroke
				(width 0.1)
				(type default)
			)
			(layer "F.Fab")
		)
		(fp_line
			(start 0.120396 0.2794)
			(end -0.12065 0.2794)
			(stroke
				(width 0.1)
				(type default)
			)
			(layer "F.Fab")
		)
		(fp_line
			(start 0.120396 0.3048)
			(end 0.120396 0.2794)
			(stroke
				(width 0.1)
				(type default)
			)
			(layer "F.Fab")
		)
		(fp_line
			(start 0.12065 -0.3048)
			(end 0.67945 -0.3048)
			(stroke
				(width 0.1)
				(type default)
			)
			(layer "F.Fab")
		)
		(fp_line
			(start 0.12065 -0.2794)
			(end 0.12065 -0.3048)
			(stroke
				(width 0.1)
				(type default)
			)
			(layer "F.Fab")
		)
		(fp_line
			(start 0.67945 -0.3048)
			(end 0.67945 0.3048)
			(stroke
				(width 0.1)
				(type default)
			)
			(layer "F.Fab")
		)
		(fp_line
			(start 0.67945 0.3048)
			(end 0.120396 0.3048)
			(stroke
				(width 0.1)
				(type default)
			)
			(layer "F.Fab")
		)
		(pad "1" smd circle
			(at -0.40005 0)
			(size 0 0)
			(layers "F.Cu" "F.Mask" "F.Paste")
			(net "P12V_SSD5_OCP")
		)
		(pad "2" smd circle
			(at 0.40005 0)
			(size 0 0)
			(layers "F.Cu" "F.Mask" "F.Paste")
			(net "GND")
		)
	)
)
